(kicad_pcb
	(version 20240108)
	(generator "pcbnew")
	(generator_version "8.0")
	(general
		(thickness 1.6)
		(legacy_teardrops no)
	)
	(paper "A4")
	(title_block
		(title "Jetson Orin Baseboard OCuLink Expansion")
		(date "2025-03-18")
		(rev "1.1.0")
		(company "Antmicro Ltd")
		(comment 1 "www.antmicro.com")
		(comment 9 "footprints 68-71 of 119")
	)
	(layers
		(0 "F.Cu" signal)
		(1 "In1.Cu" signal)
		(2 "In2.Cu" signal)
		(31 "B.Cu" signal)
		(32 "B.Adhes" user "B.Adhesive")
		(33 "F.Adhes" user "F.Adhesive")
		(34 "B.Paste" user)
		(35 "F.Paste" user)
		(36 "B.SilkS" user "B.Silkscreen")
		(37 "F.SilkS" user "F.Silkscreen")
		(38 "B.Mask" user)
		(39 "F.Mask" user)
		(40 "Dwgs.User" user "User.Drawings")
		(41 "Cmts.User" user "User.Comments")
		(42 "Eco1.User" user "User.Eco1")
		(43 "Eco2.User" user "User.Eco2")
		(44 "Edge.Cuts" user)
		(45 "Margin" user)
		(46 "B.CrtYd" user "B.Courtyard")
		(47 "F.CrtYd" user "F.Courtyard")
		(48 "B.Fab" user)
		(49 "F.Fab" user)
	)
	(footprint "antmicro-footprints:R_0402_1005Metric"
		(layer "B.Cu")
		(at 130.5 116.23 180)
		(descr "Resistor SMD 0402")
		(tags "resistor SMD 0402")
		(property "Reference" "R41"
			(at -2.946 -0.391749 0)
			(layer "B.SilkS")
			(effects
				(font
					(size 0.7 0.7)
					(thickness 0.15)
				)
				(justify left bottom mirror)
			)
		)
		(property "Value" "R_10k_0402"
			(at -1.011843 -1.772047 0)
			(layer "B.Fab")
			(effects
				(font
					(size 0.7 0.7)
					(thickness 0.15)
				)
				(justify left bottom mirror)
			)
		)
		(property "Footprint" "antmicro-footprints:R_0402_1005Metric"
			(at 0 0 0)
			(layer "B.Fab")
			(hide yes)
			(effects
				(font
					(size 1.27 1.27)
					(thickness 0.15)
				)
				(justify mirror)
			)
		)
		(property "Datasheet" "https://www.bourns.com/docs/product-datasheets/cr.pdf"
			(at 0 0 0)
			(layer "B.Fab")
			(hide yes)
			(effects
				(font
					(size 1.27 1.27)
					(thickness 0.15)
				)
				(justify mirror)
			)
		)
		(property "Description" "SMD Chip Resistor, 10 kohm, ± 1%, 62.5 mW, 0402 [1005 Metric], Thick Film, General Purpose"
			(at 0 0 0)
			(layer "B.Fab")
			(hide yes)
			(effects
				(font
					(size 1.27 1.27)
					(thickness 0.15)
				)
				(justify mirror)
			)
		)
		(property "MPN" "CR0402-FX-1002GLF"
			(at 0 0 0)
			(unlocked yes)
			(layer "B.Fab")
			(hide yes)
			(effects
				(font
					(size 1 1)
					(thickness 0.15)
				)
				(justify mirror)
			)
		)
		(property "Manufacturer" "Bourns"
			(at 0 0 0)
			(unlocked yes)
			(layer "B.Fab")
			(hide yes)
			(effects
				(font
					(size 1 1)
					(thickness 0.15)
				)
				(justify mirror)
			)
		)
		(property "License" "Apache-2.0"
			(at 0 0 0)
			(unlocked yes)
			(layer "B.Fab")
			(hide yes)
			(effects
				(font
					(size 1 1)
					(thickness 0.15)
				)
				(justify mirror)
			)
		)
		(property "Author" "Antmicro"
			(at 0 0 0)
			(unlocked yes)
			(layer "B.Fab")
			(hide yes)
			(effects
				(font
					(size 1 1)
					(thickness 0.15)
				)
				(justify mirror)
			)
		)
		(property "Val" "10k"
			(at 0 0 0)
			(unlocked yes)
			(layer "B.Fab")
			(hide yes)
			(effects
				(font
					(size 1 1)
					(thickness 0.15)
				)
				(justify mirror)
			)
		)
		(property "Tolerance" "1%"
			(at 0 0 0)
			(unlocked yes)
			(layer "B.Fab")
			(hide yes)
			(effects
				(font
					(size 1 1)
					(thickness 0.15)
				)
				(justify mirror)
			)
		)
		(sheetname "Root")
		(sheetfile "jetson-orin-baseboard-oculink-expansion.kicad_sch")
		(attr smd)
		(fp_rect
			(start -0.925 0.47)
			(end 0.925 -0.47)
			(stroke
				(width 0.05)
				(type default)
			)
			(fill none)
			(layer "B.CrtYd")
		)
		(fp_rect
			(start -0.5 0.25)
			(end 0.5 -0.25)
			(stroke
				(width 0.15)
				(type solid)
			)
			(fill none)
			(layer "B.Fab")
		)
		(fp_text user "License: Apache-2.0"
			(at -0.95 -5.169 0)
			(layer "B.Fab")
			(hide yes)
			(effects
				(font
					(size 0.7 0.7)
					(thickness 0.15)
				)
				(justify left bottom mirror)
			)
		)
		(fp_text user "Author: Antmicro"
			(at -0.95 -4.169 0)
			(layer "B.Fab")
			(hide yes)
			(effects
				(font
					(size 0.7 0.7)
					(thickness 0.15)
				)
				(justify left bottom mirror)
			)
		)
		(fp_text user "${REFERENCE}"
			(at -0.95 -3.168 0)
			(layer "B.Fab")
			(hide yes)
			(effects
				(font
					(size 0.7 0.7)
					(thickness 0.15)
				)
				(justify left bottom mirror)
			)
		)
		(pad "1" smd roundrect
			(at -0.48 0 180)
			(size 0.59 0.64)
			(layers "B.Cu" "B.Paste" "B.Mask")
			(roundrect_rratio 0.25)
			(net 106 "Net-(U2-SCL)")
			(pintype "passive")
		)
		(pad "2" smd roundrect
			(at 0.48 0 180)
			(size 0.59 0.64)
			(layers "B.Cu" "B.Paste" "B.Mask")
			(roundrect_rratio 0.25)
			(net 23 "+3V3")
			(pintype "passive")
		)
	)
	(footprint "antmicro-footprints:C_0402_1005Metric"
		(layer "B.Cu")
		(at 121.275 125.795 90)
		(descr "Capacitor SMD 0402")
		(tags "capacitor SMD 0402")
		(property "Reference" "C22"
			(at 1.605 -0.385 90)
			(layer "B.SilkS")
			(effects
				(font
					(size 0.7 0.7)
					(thickness 0.15)
				)
				(justify right top mirror)
			)
		)
		(property "Value" "C_100n_0402"
			(at -1.022927 -2.155213 90)
			(layer "B.Fab")
			(effects
				(font
					(size 0.7 0.7)
					(thickness 0.15)
				)
				(justify right top mirror)
			)
		)
		(property "Footprint" "antmicro-footprints:C_0402_1005Metric"
			(at 0 0 90)
			(layer "B.Fab")
			(hide yes)
			(effects
				(font
					(size 1.27 1.27)
					(thickness 0.15)
				)
				(justify mirror)
			)
		)
		(property "Datasheet" "https://www.murata.com/products/productdetail?partno=GRM155R61H104KE14%23"
			(at 0 0 90)
			(layer "B.Fab")
			(hide yes)
			(effects
				(font
					(size 1.27 1.27)
					(thickness 0.15)
				)
				(justify mirror)
			)
		)
		(property "Description" "SMD Multilayer Ceramic Capacitor, 0.1 µF, 50 V, 0402 [1005 Metric], ± 10%, X5R, GRM Series"
			(at 0 0 90)
			(layer "B.Fab")
			(hide yes)
			(effects
				(font
					(size 1.27 1.27)
					(thickness 0.15)
				)
				(justify mirror)
			)
		)
		(property "MPN" "GRM155R61H104KE14D"
			(at 0 0 -90)
			(unlocked yes)
			(layer "B.Fab")
			(hide yes)
			(effects
				(font
					(size 1 1)
					(thickness 0.15)
				)
				(justify mirror)
			)
		)
		(property "Manufacturer" "Murata"
			(at 0 0 -90)
			(unlocked yes)
			(layer "B.Fab")
			(hide yes)
			(effects
				(font
					(size 1 1)
					(thickness 0.15)
				)
				(justify mirror)
			)
		)
		(property "License" "Apache-2.0"
			(at 0 0 -90)
			(unlocked yes)
			(layer "B.Fab")
			(hide yes)
			(effects
				(font
					(size 1 1)
					(thickness 0.15)
				)
				(justify mirror)
			)
		)
		(property "Author" "Antmicro"
			(at 0 0 -90)
			(unlocked yes)
			(layer "B.Fab")
			(hide yes)
			(effects
				(font
					(size 1 1)
					(thickness 0.15)
				)
				(justify mirror)
			)
		)
		(property "Val" "100n"
			(at 0 0 -90)
			(unlocked yes)
			(layer "B.Fab")
			(hide yes)
			(effects
				(font
					(size 1 1)
					(thickness 0.15)
				)
				(justify mirror)
			)
		)
		(property "Voltage" "50V"
			(at 0 0 -90)
			(unlocked yes)
			(layer "B.Fab")
			(hide yes)
			(effects
				(font
					(size 1 1)
					(thickness 0.15)
				)
				(justify mirror)
			)
		)
		(property "Dielectric" "X5R"
			(at 0 0 -90)
			(unlocked yes)
			(layer "B.Fab")
			(hide yes)
			(effects
				(font
					(size 1 1)
					(thickness 0.15)
				)
				(justify mirror)
			)
		)
		(property "Public" "False"
			(at 0 0 -90)
			(unlocked yes)
			(layer "B.Fab")
			(hide yes)
			(effects
				(font
					(size 1 1)
					(thickness 0.15)
				)
				(justify mirror)
			)
		)
		(sheetname "Root")
		(sheetfile "jetson-orin-baseboard-oculink-expansion.kicad_sch")
		(attr smd)
		(fp_rect
			(start -0.925 0.47)
			(end 0.925 -0.47)
			(stroke
				(width 0.05)
				(type default)
			)
			(fill none)
			(layer "B.CrtYd")
		)
		(fp_line
			(start 0.504 -0.248)
			(end 0.504 0.25)
			(stroke
				(width 0.15)
				(type solid)
			)
			(layer "B.Fab")
		)
		(fp_line
			(start -0.494 -0.248)
			(end 0.504 -0.248)
			(stroke
				(width 0.15)
				(type solid)
			)
			(layer "B.Fab")
		)
		(fp_line
			(start 0.504 0.25)
			(end -0.494 0.25)
			(stroke
				(width 0.15)
				(type solid)
			)
			(layer "B.Fab")
		)
		(fp_line
			(start -0.494 0.25)
			(end -0.494 -0.248)
			(stroke
				(width 0.15)
				(type solid)
			)
			(layer "B.Fab")
		)
		(fp_text user "Author: Antmicro"
			(at -0.939 -3.399 90)
			(layer "B.Fab")
			(hide yes)
			(effects
				(font
					(size 0.7 0.7)
					(thickness 0.15)
				)
				(justify right top mirror)
			)
		)
		(fp_text user "${REFERENCE}"
			(at -0.939 -4.599 90)
			(layer "B.Fab")
			(hide yes)
			(effects
				(font
					(size 0.7 0.7)
					(thickness 0.15)
				)
				(justify right top mirror)
			)
		)
		(fp_text user "License: Apache-2.0"
			(at -0.939 -5.799 90)
			(layer "B.Fab")
			(hide yes)
			(effects
				(font
					(size 0.7 0.7)
					(thickness 0.15)
				)
				(justify right top mirror)
			)
		)
		(pad "1" smd roundrect
			(at -0.48 0 90)
			(size 0.59 0.64)
			(layers "B.Cu" "B.Paste" "B.Mask")
			(roundrect_rratio 0.25)
			(net 51 "GND")
			(pintype "passive")
		)
		(pad "2" smd roundrect
			(at 0.48 0 90)
			(size 0.59 0.64)
			(layers "B.Cu" "B.Paste" "B.Mask")
			(roundrect_rratio 0.25)
			(net 23 "+3V3")
			(pintype "passive")
		)
	)
	(footprint "antmicro-footprints:C_0402_1005Metric"
		(layer "B.Cu")
		(at 122.775 127.913 -90)
		(descr "Capacitor SMD 0402")
		(tags "capacitor SMD 0402")
		(property "Reference" "C19"
			(at 1.627 -0.445 90)
			(layer "B.SilkS")
			(effects
				(font
					(size 0.7 0.7)
					(thickness 0.15)
				)
				(justify left bottom mirror)
			)
		)
		(property "Value" "C_100n_0402"
			(at -1.022927 -2.155213 90)
			(layer "B.Fab")
			(effects
				(font
					(size 0.7 0.7)
					(thickness 0.15)
				)
				(justify left bottom mirror)
			)
		)
		(property "Footprint" "antmicro-footprints:C_0402_1005Metric"
			(at 0 0 90)
			(layer "B.Fab")
			(hide yes)
			(effects
				(font
					(size 1.27 1.27)
					(thickness 0.15)
				)
				(justify mirror)
			)
		)
		(property "Datasheet" "https://www.murata.com/products/productdetail?partno=GRM155R61H104KE14%23"
			(at 0 0 90)
			(layer "B.Fab")
			(hide yes)
			(effects
				(font
					(size 1.27 1.27)
					(thickness 0.15)
				)
				(justify mirror)
			)
		)
		(property "Description" "SMD Multilayer Ceramic Capacitor, 0.1 µF, 50 V, 0402 [1005 Metric], ± 10%, X5R, GRM Series"
			(at 0 0 90)
			(layer "B.Fab")
			(hide yes)
			(effects
				(font
					(size 1.27 1.27)
					(thickness 0.15)
				)
				(justify mirror)
			)
		)
		(property "MPN" "GRM155R61H104KE14D"
			(at 0 0 90)
			(unlocked yes)
			(layer "B.Fab")
			(hide yes)
			(effects
				(font
					(size 1 1)
					(thickness 0.15)
				)
				(justify mirror)
			)
		)
		(property "Manufacturer" "Murata"
			(at 0 0 90)
			(unlocked yes)
			(layer "B.Fab")
			(hide yes)
			(effects
				(font
					(size 1 1)
					(thickness 0.15)
				)
				(justify mirror)
			)
		)
		(property "License" "Apache-2.0"
			(at 0 0 90)
			(unlocked yes)
			(layer "B.Fab")
			(hide yes)
			(effects
				(font
					(size 1 1)
					(thickness 0.15)
				)
				(justify mirror)
			)
		)
		(property "Author" "Antmicro"
			(at 0 0 90)
			(unlocked yes)
			(layer "B.Fab")
			(hide yes)
			(effects
				(font
					(size 1 1)
					(thickness 0.15)
				)
				(justify mirror)
			)
		)
		(property "Val" "100n"
			(at 0 0 90)
			(unlocked yes)
			(layer "B.Fab")
			(hide yes)
			(effects
				(font
					(size 1 1)
					(thickness 0.15)
				)
				(justify mirror)
			)
		)
		(property "Voltage" "50V"
			(at 0 0 90)
			(unlocked yes)
			(layer "B.Fab")
			(hide yes)
			(effects
				(font
					(size 1 1)
					(thickness 0.15)
				)
				(justify mirror)
			)
		)
		(property "Dielectric" "X5R"
			(at 0 0 90)
			(unlocked yes)
			(layer "B.Fab")
			(hide yes)
			(effects
				(font
					(size 1 1)
					(thickness 0.15)
				)
				(justify mirror)
			)
		)
		(property "Public" "False"
			(at 0 0 90)
			(unlocked yes)
			(layer "B.Fab")
			(hide yes)
			(effects
				(font
					(size 1 1)
					(thickness 0.15)
				)
				(justify mirror)
			)
		)
		(sheetname "Root")
		(sheetfile "jetson-orin-baseboard-oculink-expansion.kicad_sch")
		(attr smd)
		(fp_rect
			(start -0.925 0.47)
			(end 0.925 -0.47)
			(stroke
				(width 0.05)
				(type default)
			)
			(fill none)
			(layer "B.CrtYd")
		)
		(fp_line
			(start -0.494 0.25)
			(end -0.494 -0.248)
			(stroke
				(width 0.15)
				(type solid)
			)
			(layer "B.Fab")
		)
		(fp_line
			(start 0.504 0.25)
			(end -0.494 0.25)
			(stroke
				(width 0.15)
				(type solid)
			)
			(layer "B.Fab")
		)
		(fp_line
			(start -0.494 -0.248)
			(end 0.504 -0.248)
			(stroke
				(width 0.15)
				(type solid)
			)
			(layer "B.Fab")
		)
		(fp_line
			(start 0.504 -0.248)
			(end 0.504 0.25)
			(stroke
				(width 0.15)
				(type solid)
			)
			(layer "B.Fab")
		)
		(fp_text user "Author: Antmicro"
			(at -0.939 -3.399 90)
			(layer "B.Fab")
			(hide yes)
			(effects
				(font
					(size 0.7 0.7)
					(thickness 0.15)
				)
				(justify left bottom mirror)
			)
		)
		(fp_text user "License: Apache-2.0"
			(at -0.939 -5.799 90)
			(layer "B.Fab")
			(hide yes)
			(effects
				(font
					(size 0.7 0.7)
					(thickness 0.15)
				)
				(justify left bottom mirror)
			)
		)
		(fp_text user "${REFERENCE}"
			(at -0.939 -4.599 90)
			(layer "B.Fab")
			(hide yes)
			(effects
				(font
					(size 0.7 0.7)
					(thickness 0.15)
				)
				(justify left bottom mirror)
			)
		)
		(pad "1" smd roundrect
			(at -0.48 0 270)
			(size 0.59 0.64)
			(layers "B.Cu" "B.Paste" "B.Mask")
			(roundrect_rratio 0.25)
			(net 51 "GND")
			(pintype "passive")
		)
		(pad "2" smd roundrect
			(at 0.48 0 270)
			(size 0.59 0.64)
			(layers "B.Cu" "B.Paste" "B.Mask")
			(roundrect_rratio 0.25)
			(net 23 "+3V3")
			(pintype "passive")
		)
	)
	(footprint "antmicro-footprints:R_0402_1005Metric"
		(layer "B.Cu")
		(at 127.944 125.32775)
		(descr "Resistor SMD 0402")
		(tags "resistor SMD 0402")
		(property "Reference" "R23"
			(at -3.274 -0.37775 0)
			(layer "B.SilkS")
			(effects
				(font
					(size 0.7 0.7)
					(thickness 0.15)
				)
				(justify right top mirror)
			)
		)
		(property "Value" "R_1k_0402"
			(at -1.011843 -1.772047 0)
			(layer "B.Fab")
			(effects
				(font
					(size 0.7 0.7)
					(thickness 0.15)
				)
				(justify right top mirror)
			)
		)
		(property "Footprint" "antmicro-footprints:R_0402_1005Metric"
			(at 0 0 0)
			(layer "B.Fab")
			(hide yes)
			(effects
				(font
					(size 1.27 1.27)
					(thickness 0.15)
				)
				(justify mirror)
			)
		)
		(property "Datasheet" "https://www.bourns.com/docs/product-datasheets/cr.pdf"
			(at 0 0 0)
			(layer "B.Fab")
			(hide yes)
			(effects
				(font
					(size 1.27 1.27)
					(thickness 0.15)
				)
				(justify mirror)
			)
		)
		(property "Description" "SMD Chip Resistor, 1 kohm, ± 1%, 63 mW, 0402 [1005 Metric], Thick Film, General Purpose"
			(at 0 0 0)
			(layer "B.Fab")
			(hide yes)
			(effects
				(font
					(size 1.27 1.27)
					(thickness 0.15)
				)
				(justify mirror)
			)
		)
		(property "MPN" "CR0402-FX-1001GLF"
			(at 0 0 180)
			(unlocked yes)
			(layer "B.Fab")
			(hide yes)
			(effects
				(font
					(size 1 1)
					(thickness 0.15)
				)
				(justify mirror)
			)
		)
		(property "Manufacturer" "Bourns"
			(at 0 0 180)
			(unlocked yes)
			(layer "B.Fab")
			(hide yes)
			(effects
				(font
					(size 1 1)
					(thickness 0.15)
				)
				(justify mirror)
			)
		)
		(property "License" "Apache-2.0"
			(at 0 0 180)
			(unlocked yes)
			(layer "B.Fab")
			(hide yes)
			(effects
				(font
					(size 1 1)
					(thickness 0.15)
				)
				(justify mirror)
			)
		)
		(property "Author" "Antmicro"
			(at 0 0 180)
			(unlocked yes)
			(layer "B.Fab")
			(hide yes)
			(effects
				(font
					(size 1 1)
					(thickness 0.15)
				)
				(justify mirror)
			)
		)
		(property "Val" "1k"
			(at 0 0 180)
			(unlocked yes)
			(layer "B.Fab")
			(hide yes)
			(effects
				(font
					(size 1 1)
					(thickness 0.15)
				)
				(justify mirror)
			)
		)
		(property "Tolerance" "1%"
			(at 0 0 180)
			(unlocked yes)
			(layer "B.Fab")
			(hide yes)
			(effects
				(font
					(size 1 1)
					(thickness 0.15)
				)
				(justify mirror)
			)
		)
		(property "Public" "False"
			(at 0 0 180)
			(unlocked yes)
			(layer "B.Fab")
			(hide yes)
			(effects
				(font
					(size 1 1)
					(thickness 0.15)
				)
				(justify mirror)
			)
		)
		(sheetname "Root")
		(sheetfile "jetson-orin-baseboard-oculink-expansion.kicad_sch")
		(attr smd dnp)
		(fp_rect
			(start -0.925 0.47)
			(end 0.925 -0.47)
			(stroke
				(width 0.05)
				(type default)
			)
			(fill none)
			(layer "B.CrtYd")
		)
		(fp_rect
			(start -0.5 0.25)
			(end 0.5 -0.25)
			(stroke
				(width 0.15)
				(type solid)
			)
			(fill none)
			(layer "B.Fab")
		)
		(fp_text user "Author: Antmicro"
			(at -0.95 -4.169 0)
			(layer "B.Fab")
			(hide yes)
			(effects
				(font
					(size 0.7 0.7)
					(thickness 0.15)
				)
				(justify right top mirror)
			)
		)
		(fp_text user "${REFERENCE}"
			(at -0.95 -3.168 0)
			(layer "B.Fab")
			(hide yes)
			(effects
				(font
					(size 0.7 0.7)
					(thickness 0.15)
				)
				(justify right top mirror)
			)
		)
		(fp_text user "License: Apache-2.0"
			(at -0.95 -5.169 0)
			(layer "B.Fab")
			(hide yes)
			(effects
				(font
					(size 0.7 0.7)
					(thickness 0.15)
				)
				(justify right top mirror)
			)
		)
		(pad "1" smd roundrect
			(at -0.48 0)
			(size 0.59 0.64)
			(layers "B.Cu" "B.Paste" "B.Mask")
			(roundrect_rratio 0.25)
			(net 23 "+3V3")
			(pintype "passive")
		)
		(pad "2" smd roundrect
			(at 0.48 0)
			(size 0.59 0.64)
			(layers "B.Cu" "B.Paste" "B.Mask")
			(roundrect_rratio 0.25)
			(net 99 "/TX_EQ2")
			(pintype "passive")
		)
	)
)
